(kicad_pcb
	(version 20260206)
	(generator "pcbnew")
	(generator_version "10.0")
	(general
		(thickness 1.21888)
		(legacy_teardrops no)
	)
	(paper "A4")
	(title_block
		(title "timecard-v9 — TimeCard-DC-V9_EXP.PcbDoc")
		(comment 1 "Time Appliance Project (Time Card) / footprints 82-89 of 402")
	)
	(layers
		(0 "F.Cu" signal "TOP")
		(4 "In1.Cu" signal "SGND")
		(6 "In2.Cu" signal "IN1")
		(8 "In3.Cu" signal "IN2")
		(10 "In4.Cu" signal "SGND1")
		(2 "B.Cu" signal "BOTTOM")
		(9 "F.Adhes" user "F.Adhesive")
		(11 "B.Adhes" user "B.Adhesive")
		(13 "F.Paste" user "Top Paste")
		(15 "B.Paste" user "Bottom Paste")
		(5 "F.SilkS" user "Top Overlay")
		(7 "B.SilkS" user "Bottom Overlay")
		(1 "F.Mask" user "Top Solder")
		(3 "B.Mask" user "Bottom Solder")
		(17 "Dwgs.User" user "User.Drawings")
		(19 "Cmts.User" user "User.Comments")
		(21 "Eco1.User" user "User.Eco1")
		(23 "Eco2.User" user "User.Eco2")
		(25 "Edge.Cuts" user)
		(27 "Margin" user)
		(31 "F.CrtYd" user "Top Courtyard")
		(29 "B.CrtYd" user "Bottom Courtyard")
		(35 "F.Fab" user "Top Component Center")
		(33 "B.Fab" user "Bottom Component Center")
	)
	(footprint "Vault:FP-T521X476M035ATE030-MFG"
		(layer "F.Cu")
		(at 187.4216 92.7162 90)
		(property "Reference" "C73"
			(at 1.4968 3.073069 270)
			(unlocked yes)
			(layer "F.SilkS")
			(effects
				(font
					(size 0.762 0.762)
					(thickness 0.2032)
				)
			)
		)
		(property "Value" "47uF_35V_2917"
			(at -5.843751 7.45182 0)
			(unlocked yes)
			(layer "F.SilkS")
			(hide yes)
			(effects
				(font
					(size 0.762 0.762)
					(thickness 0.2032)
				)
			)
		)
		(sheetname "03-POWER")
		(sheetfile "03-POWER.kicad_sch")
		(duplicate_pad_numbers_are_jumpers no)
		(fp_line
			(start 3.8 -2.3)
			(end 3.8 -1.54)
			(stroke
				(width 0.2)
				(type solid)
			)
			(layer "F.SilkS")
		)
		(fp_line
			(start -3.8 -2.3)
			(end 3.8 -2.3)
			(stroke
				(width 0.2)
				(type solid)
			)
			(layer "F.SilkS")
		)
		(fp_line
			(start -3.8 -2.3)
			(end -3.8 -1.54)
			(stroke
				(width 0.2)
				(type solid)
			)
			(layer "F.SilkS")
		)
		(fp_line
			(start 4.7 -0.3)
			(end 4.7 0.3)
			(stroke
				(width 0.2)
				(type solid)
			)
			(layer "F.SilkS")
		)
		(fp_line
			(start 4.4 0)
			(end 5 0)
			(stroke
				(width 0.2)
				(type solid)
			)
			(layer "F.SilkS")
		)
		(fp_line
			(start 3.8 1.54)
			(end 3.8 2.3)
			(stroke
				(width 0.2)
				(type solid)
			)
			(layer "F.SilkS")
		)
		(fp_line
			(start -3.8 1.54)
			(end -3.8 2.3)
			(stroke
				(width 0.2)
				(type solid)
			)
			(layer "F.SilkS")
		)
		(fp_line
			(start -3.8 2.3)
			(end 3.8 2.3)
			(stroke
				(width 0.2)
				(type solid)
			)
			(layer "F.SilkS")
		)
		(fp_line
			(start 4.13 -2.42)
			(end 4.13 2.42)
			(stroke
				(width 0.2)
				(type solid)
			)
			(layer "F.CrtYd")
		)
		(fp_line
			(start -4.13 -2.42)
			(end 4.13 -2.42)
			(stroke
				(width 0.2)
				(type solid)
			)
			(layer "F.CrtYd")
		)
		(fp_line
			(start -4.13 -2.42)
			(end -4.13 2.42)
			(stroke
				(width 0.2)
				(type solid)
			)
			(layer "F.CrtYd")
		)
		(fp_line
			(start -4.13 2.42)
			(end 4.13 2.42)
			(stroke
				(width 0.2)
				(type solid)
			)
			(layer "F.CrtYd")
		)
		(fp_line
			(start 4.13 -2.42)
			(end 4.13 2.42)
			(stroke
				(width 0.2)
				(type solid)
			)
			(layer "F.Fab")
		)
		(fp_line
			(start -4.13 -2.42)
			(end 4.13 -2.42)
			(stroke
				(width 0.2)
				(type solid)
			)
			(layer "F.Fab")
		)
		(fp_line
			(start -4.13 -2.42)
			(end -4.13 2.42)
			(stroke
				(width 0.2)
				(type solid)
			)
			(layer "F.Fab")
		)
		(fp_line
			(start 0 -0.5)
			(end 0 0.5)
			(stroke
				(width 0.1)
				(type solid)
			)
			(layer "F.Fab")
		)
		(fp_line
			(start -0.5 0)
			(end 0.5 0)
			(stroke
				(width 0.1)
				(type solid)
			)
			(layer "F.Fab")
		)
		(fp_line
			(start -4.13 2.42)
			(end 4.13 2.42)
			(stroke
				(width 0.2)
				(type solid)
			)
			(layer "F.Fab")
		)
		(fp_text user "${REFERENCE}"
			(at 0 0.28425 90)
			(unlocked yes)
			(layer "F.Fab")
			(effects
				(font
					(face "Arial")
					(size 0.63 0.63)
					(thickness 0.1)
				)
				(justify left bottom)
			)
		)
		(pad "1" smd rect
			(at -3.01 0 90)
			(size 1.99 2.33)
			(layers "F.Cu" "F.Mask" "F.Paste")
			(net "GND")
			(solder_mask_margin 0)
			(solder_paste_margin 0)
		)
		(pad "2" smd rect
			(at 3.01 0 90)
			(size 1.99 2.33)
			(layers "F.Cu" "F.Mask" "F.Paste")
			(net "+12V")
			(solder_mask_margin 0)
			(solder_paste_margin 0)
		)
	)
	(footprint "Vault:FP-C0603C105K3PACTU-MFG"
		(layer "F.Cu")
		(at 86.70687 86.4137 -90)
		(property "Reference" "C38"
			(at -0.32859 2.973079 90)
			(unlocked yes)
			(layer "F.SilkS")
			(effects
				(font
					(size 0.762 0.762)
					(thickness 0.2286)
				)
			)
		)
		(property "Value" "1uF"
			(at -2.859271 1.45989 180)
			(unlocked yes)
			(layer "F.SilkS")
			(hide yes)
			(effects
				(font
					(size 0.762 0.762)
					(thickness 0.2286)
				)
			)
		)
		(sheetname "02-USER_IO_STATUS")
		(sheetfile "02-USER_IO_STATUS.kicad_sch")
		(duplicate_pad_numbers_are_jumpers no)
		(fp_line
			(start 0.875 0.825)
			(end -0.875 0.825)
			(stroke
				(width 0.2)
				(type solid)
			)
			(layer "F.SilkS")
		)
		(fp_line
			(start 0.875 -0.825)
			(end -0.875 -0.825)
			(stroke
				(width 0.2)
				(type solid)
			)
			(layer "F.SilkS")
		)
		(fp_line
			(start -1.2 0.6)
			(end -1.2 -0.59999)
			(stroke
				(width 0.2)
				(type solid)
			)
			(layer "F.CrtYd")
		)
		(fp_line
			(start 1.2 0.6)
			(end -1.2 0.6)
			(stroke
				(width 0.2)
				(type solid)
			)
			(layer "F.CrtYd")
		)
		(fp_line
			(start 1.2 0.6)
			(end 1.2 -0.59999)
			(stroke
				(width 0.2)
				(type solid)
			)
			(layer "F.CrtYd")
		)
		(fp_line
			(start 1.2 -0.59999)
			(end -1.2 -0.59999)
			(stroke
				(width 0.2)
				(type solid)
			)
			(layer "F.CrtYd")
		)
		(fp_line
			(start -1.2 0.6)
			(end -1.2 -0.59999)
			(stroke
				(width 0.2)
				(type solid)
			)
			(layer "F.Fab")
		)
		(fp_line
			(start 1.2 0.6)
			(end -1.2 0.6)
			(stroke
				(width 0.2)
				(type solid)
			)
			(layer "F.Fab")
		)
		(fp_line
			(start 1.2 0.6)
			(end 1.2 -0.59999)
			(stroke
				(width 0.2)
				(type solid)
			)
			(layer "F.Fab")
		)
		(fp_line
			(start 0 0.5)
			(end 0 -0.49999)
			(stroke
				(width 0.1)
				(type solid)
			)
			(layer "F.Fab")
		)
		(fp_line
			(start 0.5 0)
			(end -0.5 0)
			(stroke
				(width 0.1)
				(type solid)
			)
			(layer "F.Fab")
		)
		(fp_line
			(start 1.2 -0.59999)
			(end -1.2 -0.59999)
			(stroke
				(width 0.2)
				(type solid)
			)
			(layer "F.Fab")
		)
		(pad "1" smd rect
			(at -0.6 0 270)
			(size 0.75 0.9)
			(layers "F.Cu" "F.Mask" "F.Paste")
			(net "+3.3V")
			(solder_mask_margin 0)
			(solder_paste_margin 0)
		)
		(pad "2" smd rect
			(at 0.6 0 270)
			(size 0.75 0.9)
			(layers "F.Cu" "F.Mask" "F.Paste")
			(net "GND")
			(solder_mask_margin 0)
			(solder_paste_margin 0)
		)
	)
	(footprint "Vault:RESC1005X40X25LL05T10"
		(layer "F.Cu")
		(at 196.2216 129.7162 90)
		(property "Reference" "R143"
			(at 2.5032 0.226931 90)
			(unlocked yes)
			(layer "F.SilkS")
			(effects
				(font
					(size 0.762 0.762)
					(thickness 0.2032)
				)
			)
		)
		(property "Value" "49.9_1%_0402"
			(at -2.579871 8.798265 0)
			(unlocked yes)
			(layer "F.SilkS")
			(hide yes)
			(effects
				(font
					(size 0.762 0.762)
					(thickness 0.2032)
				)
			)
		)
		(sheetname "11-M2_RCB_MUX")
		(sheetfile "11-M2_RCB_MUX.kicad_sch")
		(duplicate_pad_numbers_are_jumpers no)
		(pad "1" smd rect
			(at -0.375 0 180)
			(size 0.45 0.5)
			(layers "F.Cu" "F.Mask" "F.Paste")
			(net "NetR143_1")
		)
		(pad "2" smd rect
			(at 0.375 0 180)
			(size 0.45 0.5)
			(layers "F.Cu" "F.Mask" "F.Paste")
			(net "GPS2_TP2")
		)
	)
	(footprint "Vault:RESC1005X40X25LL05T10"
		(layer "F.Cu")
		(at 194.8216 120.0162 90)
		(property "Reference" "R171"
			(at 2.5032 0.026931 90)
			(unlocked yes)
			(layer "F.SilkS")
			(effects
				(font
					(size 0.762 0.762)
					(thickness 0.2032)
				)
			)
		)
		(property "Value" "49.9_1%_0402"
			(at -2.579871 8.798265 0)
			(unlocked yes)
			(layer "F.SilkS")
			(hide yes)
			(effects
				(font
					(size 0.762 0.762)
					(thickness 0.2032)
				)
			)
		)
		(sheetname "11-M2_RCB_MUX")
		(sheetfile "11-M2_RCB_MUX.kicad_sch")
		(duplicate_pad_numbers_are_jumpers no)
		(pad "1" smd rect
			(at -0.375 0 180)
			(size 0.45 0.5)
			(layers "F.Cu" "F.Mask" "F.Paste")
			(net "NetR171_1")
		)
		(pad "2" smd rect
			(at 0.375 0 180)
			(size 0.45 0.5)
			(layers "F.Cu" "F.Mask" "F.Paste")
			(net "GPS2_PIN11")
		)
	)
	(footprint "Vault:RESC1005X40X25NL10T10"
		(layer "F.Cu")
		(at 175.3216 110.9162)
		(property "Reference" "R114"
			(at 0.8032 -1.273069 0)
			(unlocked yes)
			(layer "F.SilkS")
			(effects
				(font
					(size 0.762 0.762)
					(thickness 0.2032)
				)
			)
		)
		(property "Value" "4.7K_1%_0402"
			(at -2.732281 8.747465 270)
			(unlocked yes)
			(layer "F.SilkS")
			(hide yes)
			(effects
				(font
					(size 0.762 0.762)
					(thickness 0.2032)
				)
			)
		)
		(sheetname "08-DIPSwitches_I2C")
		(sheetfile "08-DIPSwitches_I2C.kicad_sch")
		(duplicate_pad_numbers_are_jumpers no)
		(pad "1" smd rect
			(at -0.425 0 90)
			(size 0.6 0.65)
			(layers "F.Cu" "F.Mask" "F.Paste")
			(net "DC_I2C_SCL")
		)
		(pad "2" smd rect
			(at 0.425 0 90)
			(size 0.6 0.65)
			(layers "F.Cu" "F.Mask" "F.Paste")
			(net "+3.3V")
		)
	)
	(footprint "Vault:RESC1608X55X25NL10T15"
		(layer "F.Cu")
		(at 72.4216 141.0162 90)
		(property "Reference" "R34"
			(at 0.1286 -1.673069 90)
			(unlocked yes)
			(layer "F.SilkS")
			(effects
				(font
					(size 0.762 0.762)
					(thickness 0.2286)
				)
			)
		)
		(property "Value" "49.9R"
			(at -2.884671 3.186585 0)
			(unlocked yes)
			(layer "F.SilkS")
			(hide yes)
			(effects
				(font
					(size 0.762 0.762)
					(thickness 0.2286)
				)
			)
		)
		(sheetname "01-USER_IO")
		(sheetfile "01-USER_IO.kicad_sch")
		(duplicate_pad_numbers_are_jumpers no)
		(pad "1" smd rect
			(at -0.7 0 180)
			(size 0.9 0.7)
			(layers "F.Cu" "F.Mask" "F.Paste")
			(net "NetR34_1")
		)
		(pad "2" smd rect
			(at 0.7 0 180)
			(size 0.9 0.7)
			(layers "F.Cu" "F.Mask" "F.Paste")
			(net "NetAN4_1")
		)
	)
	(footprint "Vault:SOT143-4L"
		(layer "F.Cu")
		(at 71.87161 128.1162 90)
		(property "Reference" "D2"
			(at -0.328605 2.323059 270)
			(unlocked yes)
			(layer "F.SilkS")
			(effects
				(font
					(size 0.762 0.762)
					(thickness 0.2286)
				)
			)
		)
		(property "Value" "8240136"
			(at 2.6781 3.341871 90)
			(unlocked yes)
			(layer "F.SilkS")
			(hide yes)
			(effects
				(font
					(size 0.762 0.762)
					(thickness 0.2286)
				)
			)
		)
		(sheetname "01-USER_IO")
		(sheetfile "01-USER_IO.kicad_sch")
		(duplicate_pad_numbers_are_jumpers no)
		(fp_line
			(start 2.05 -1.7)
			(end 2.05 1.7)
			(stroke
				(width 0.2)
				(type solid)
			)
			(layer "F.SilkS")
		)
		(fp_line
			(start -2.05 -1.7)
			(end 2.05 -1.7)
			(stroke
				(width 0.2)
				(type solid)
			)
			(layer "F.SilkS")
		)
		(fp_line
			(start -2.05 -1.7)
			(end -2.05 1.675)
			(stroke
				(width 0.2)
				(type solid)
			)
			(layer "F.SilkS")
		)
		(fp_line
			(start -2.05 1.7)
			(end 2.05 1.7)
			(stroke
				(width 0.2)
				(type solid)
			)
			(layer "F.SilkS")
		)
		(fp_circle
			(center -2.404 -1.075)
			(end -2.15 -1.075)
			(stroke
				(width 0.2)
				(type solid)
			)
			(fill no)
			(layer "F.SilkS")
		)
		(pad "1" smd rect
			(at -1.1 -0.75 180)
			(size 1.4 1.4)
			(layers "F.Cu" "F.Mask" "F.Paste")
			(net "GND")
		)
		(pad "2" smd rect
			(at -1.1 0.95 180)
			(size 1 1.4)
			(layers "F.Cu" "F.Mask" "F.Paste")
			(net "NetAN4_1")
		)
		(pad "3" smd rect
			(at 1.1 0.95 180)
			(size 1 1.4)
			(layers "F.Cu" "F.Mask" "F.Paste")
			(net "NetAN3_1")
		)
		(pad "4" smd rect
			(at 1.1 -0.95 180)
			(size 1 1.4)
			(layers "F.Cu" "F.Mask" "F.Paste")
			(net "+3.3V")
		)
	)
	(footprint "Vault:FP-T495D107K016ATE125-MFG"
		(layer "F.Cu")
		(at 160.1116 89.1162)
		(property "Reference" "C79"
			(at -2.3614 -2.973079 0)
			(unlocked yes)
			(layer "F.SilkS")
			(effects
				(font
					(size 0.762 0.762)
					(thickness 0.2286)
				)
			)
		)
		(property "Value" "100uF_16V_2917"
			(at -5.818351 8.010455 270)
			(unlocked yes)
			(layer "F.SilkS")
			(hide yes)
			(effects
				(font
					(size 0.762 0.762)
					(thickness 0.2286)
				)
			)
		)
		(sheetname "03-POWER")
		(sheetfile "03-POWER.kicad_sch")
		(duplicate_pad_numbers_are_jumpers no)
		(fp_line
			(start -3.8 -2.3)
			(end 3.8 -2.3)
			(stroke
				(width 0.2)
				(type solid)
			)
			(layer "F.SilkS")
		)
		(fp_line
			(start -3.8 -1.54)
			(end -3.8 -2.3)
			(stroke
				(width 0.2)
				(type solid)
			)
			(layer "F.SilkS")
		)
		(fp_line
			(start -3.8 2.3)
			(end -3.8 1.54)
			(stroke
				(width 0.2)
				(type solid)
			)
			(layer "F.SilkS")
		)
		(fp_line
			(start -3.8 2.3)
			(end 3.8 2.3)
			(stroke
				(width 0.2)
				(type solid)
			)
			(layer "F.SilkS")
		)
		(fp_line
			(start 3.8 -1.54)
			(end 3.8 -2.3)
			(stroke
				(width 0.2)
				(type solid)
			)
			(layer "F.SilkS")
		)
		(fp_line
			(start 3.8 2.3)
			(end 3.8 1.54)
			(stroke
				(width 0.2)
				(type solid)
			)
			(layer "F.SilkS")
		)
		(fp_line
			(start 4.4 0)
			(end 5 0)
			(stroke
				(width 0.2)
				(type solid)
			)
			(layer "F.SilkS")
		)
		(fp_line
			(start 4.7 0.3)
			(end 4.7 -0.3)
			(stroke
				(width 0.2)
				(type solid)
			)
			(layer "F.SilkS")
		)
		(fp_line
			(start -4.105 -2.4)
			(end 4.105 -2.4)
			(stroke
				(width 0.2)
				(type solid)
			)
			(layer "F.CrtYd")
		)
		(fp_line
			(start -4.105 2.4)
			(end -4.105 -2.4)
			(stroke
				(width 0.2)
				(type solid)
			)
			(layer "F.CrtYd")
		)
		(fp_line
			(start -4.105 2.4)
			(end 4.105 2.4)
			(stroke
				(width 0.2)
				(type solid)
			)
			(layer "F.CrtYd")
		)
		(fp_line
			(start 4.105 2.4)
			(end 4.105 -2.4)
			(stroke
				(width 0.2)
				(type solid)
			)
			(layer "F.CrtYd")
		)
		(fp_line
			(start -4.105 -2.4)
			(end 4.105 -2.4)
			(stroke
				(width 0.2)
				(type solid)
			)
			(layer "F.Fab")
		)
		(fp_line
			(start -4.105 2.4)
			(end -4.105 -2.4)
			(stroke
				(width 0.2)
				(type solid)
			)
			(layer "F.Fab")
		)
		(fp_line
			(start -4.105 2.4)
			(end 4.105 2.4)
			(stroke
				(width 0.2)
				(type solid)
			)
			(layer "F.Fab")
		)
		(fp_line
			(start -0.5 0)
			(end 0.5 0)
			(stroke
				(width 0.1)
				(type solid)
			)
			(layer "F.Fab")
		)
		(fp_line
			(start 0 0.5)
			(end 0 -0.5)
			(stroke
				(width 0.1)
				(type solid)
			)
			(layer "F.Fab")
		)
		(fp_line
			(start 4.105 2.4)
			(end 4.105 -2.4)
			(stroke
				(width 0.2)
				(type solid)
			)
			(layer "F.Fab")
		)
		(fp_text user "${REFERENCE}"
			(at 0 0.28425 360)
			(unlocked yes)
			(layer "F.Fab")
			(effects
				(font
					(face "Arial")
					(size 0.63 0.63)
					(thickness 0.1)
				)
				(justify left bottom)
			)
		)
		(pad "1" smd rect
			(at -3.01 0)
			(size 1.99 2.33)
			(layers "F.Cu" "F.Mask" "F.Paste")
			(net "GND")
			(solder_mask_margin 0)
			(solder_paste_margin 0)
		)
		(pad "2" smd rect
			(at 3.01 0)
			(size 1.99 2.33)
			(layers "F.Cu" "F.Mask" "F.Paste")
			(net "+3.3V")
			(solder_mask_margin 0)
			(solder_paste_margin 0)
		)
	)
)
